# T6G (Grand Teton) — schematic netlist excerpt (pin names and nets, part order shuffled) for the footprints in the layout excerpt that follows; sources: Cadence DE-HDL packaged netlist, KiCad conversion of 04192023_DAF0TMB3IC0_F0TG_MB_C_brd_V02_OCP.brd

R1356  Q_RES  4.7K 5% CHIP  pkg 0402LF  page 167 : A = P3V3_AUX ; B = FM_PRSNT_CPU0_N
PR204  Q_RES  0 5% CHIP  pkg 0402LF  page 213 : A = PVDDCR_CPU0_P1_VOS5 ; B = PVDDCR_CPU0_P1
C6746  Q_CAP_DIFFBUS  DIFF BUS_0.22UF 6.3V 20% X6S  pkg C0201  page 352 : \1\ = P5E_CPU1_P3_TX_BUF_C_DN<10> ; \2\ = P5E_CPU1_P3_TX_BUF_DN<10>

(kicad_pcb
	(version 20260206)
	(generator "pcbnew")
	(generator_version "10.0")
	(general
		(thickness 1.6)
		(legacy_teardrops no)
	)
	(paper "A4")
	(title_block
		(title "04192023_DAF0TMB3IC0_F0TG_MB_C_brd_V02_OCP.brd")
		(comment 1 "Grand Teton / footprints 5749-5751 of 8354")
	)
	(layers
		(0 "F.Cu" signal "TOP")
		(4 "In1.Cu" signal "GND")
		(6 "In2.Cu" signal "IN1")
		(8 "In3.Cu" signal "GND1")
		(10 "In4.Cu" signal "IN2")
		(12 "In5.Cu" signal "GND2")
		(14 "In6.Cu" signal "IN3")
		(16 "In7.Cu" signal "GND3")
		(18 "In8.Cu" signal "VCC")
		(20 "In9.Cu" signal "VCC1")
		(22 "In10.Cu" signal "GND4")
		(24 "In11.Cu" signal "IN4")
		(26 "In12.Cu" signal "GND5")
		(28 "In13.Cu" signal "IN5")
		(30 "In14.Cu" signal "GND6")
		(32 "In15.Cu" signal "IN6")
		(34 "In16.Cu" signal "GND7")
		(2 "B.Cu" signal "BOTTOM")
		(9 "F.Adhes" user "F.Adhesive")
		(11 "B.Adhes" user "B.Adhesive")
		(13 "F.Paste" user "Package Geometry/Pastemask Top")
		(15 "B.Paste" user "Package Geometry/Pastemask Bottom")
		(5 "F.SilkS" user "Ref Des/Silkscreen Top")
		(7 "B.SilkS" user "Ref Des/Silkscreen Bottom")
		(1 "F.Mask" user "Board Geometry/Soldermask Top")
		(3 "B.Mask" user "Board Geometry/Soldermask Bottom")
		(17 "Dwgs.User" user "User.Drawings")
		(19 "Cmts.User" user "User.Comments")
		(21 "Eco1.User" user "User.Eco1")
		(23 "Eco2.User" user "User.Eco2")
		(25 "Edge.Cuts" user "Board Geometry/Outline")
		(27 "Margin" user)
		(31 "F.CrtYd" user "Package Geometry/Place Bound Top")
		(29 "B.CrtYd" user "Package Geometry/Place Bound Bottom")
		(35 "F.Fab" user "Ref Des/Assembly Top")
		(33 "B.Fab" user "Ref Des/Assembly Bottom")
	)
	(footprint ""
		(layer "B.Cu")
		(at 428.98695 -34.737548 180)
		(property "Reference" "R1356"
			(at 0 0 0)
			(layer "B.SilkS")
			(hide yes)
			(effects
				(font
					(size 1.27 1.27)
				)
				(justify mirror)
			)
		)
		(property "Value" ""
			(at 0 0 0)
			(layer "B.Fab")
			(effects
				(font
					(size 1.27 1.27)
				)
				(justify mirror)
			)
		)
		(duplicate_pad_numbers_are_jumpers no)
		(fp_line
			(start 0.7874 0.4064)
			(end 0.7874 -0.4064)
			(stroke
				(width 0.1524)
				(type default)
			)
			(layer "B.SilkS")
		)
		(fp_line
			(start 0.7874 -0.4064)
			(end -0.7874 -0.4064)
			(stroke
				(width 0.1524)
				(type default)
			)
			(layer "B.SilkS")
		)
		(fp_line
			(start -0.7874 0.4064)
			(end 0.7874 0.4064)
			(stroke
				(width 0.1524)
				(type default)
			)
			(layer "B.SilkS")
		)
		(fp_line
			(start -0.7874 -0.4064)
			(end -0.7874 0.4064)
			(stroke
				(width 0.1524)
				(type default)
			)
			(layer "B.SilkS")
		)
		(fp_line
			(start 0.67945 0.3048)
			(end 0.67945 -0.305054)
			(stroke
				(width 0.1)
				(type default)
			)
			(layer "B.Fab")
		)
		(fp_line
			(start 0.67945 -0.305054)
			(end 0.12065 -0.305054)
			(stroke
				(width 0.1)
				(type default)
			)
			(layer "B.Fab")
		)
		(fp_line
			(start 0.12065 0.3048)
			(end 0.67945 0.3048)
			(stroke
				(width 0.1)
				(type default)
			)
			(layer "B.Fab")
		)
		(fp_line
			(start 0.12065 0.2794)
			(end 0.12065 0.3048)
			(stroke
				(width 0.1)
				(type default)
			)
			(layer "B.Fab")
		)
		(fp_line
			(start 0.12065 -0.2794)
			(end -0.12065 -0.2794)
			(stroke
				(width 0.1)
				(type default)
			)
			(layer "B.Fab")
		)
		(fp_line
			(start 0.12065 -0.305054)
			(end 0.12065 -0.2794)
			(stroke
				(width 0.1)
				(type default)
			)
			(layer "B.Fab")
		)
		(fp_line
			(start -0.120396 0.3048)
			(end -0.120396 0.2794)
			(stroke
				(width 0.1)
				(type default)
			)
			(layer "B.Fab")
		)
		(fp_line
			(start -0.120396 0.2794)
			(end 0.12065 0.2794)
			(stroke
				(width 0.1)
				(type default)
			)
			(layer "B.Fab")
		)
		(fp_line
			(start -0.12065 -0.2794)
			(end -0.12065 -0.3048)
			(stroke
				(width 0.1)
				(type default)
			)
			(layer "B.Fab")
		)
		(fp_line
			(start -0.12065 -0.3048)
			(end -0.67945 -0.3048)
			(stroke
				(width 0.1)
				(type default)
			)
			(layer "B.Fab")
		)
		(fp_line
			(start -0.67945 0.3048)
			(end -0.120396 0.3048)
			(stroke
				(width 0.1)
				(type default)
			)
			(layer "B.Fab")
		)
		(fp_line
			(start -0.67945 -0.3048)
			(end -0.67945 0.3048)
			(stroke
				(width 0.1)
				(type default)
			)
			(layer "B.Fab")
		)
		(pad "1" smd circle
			(at 0.40005 0)
			(size 0 0)
			(layers "B.Cu" "B.Mask" "B.Paste")
			(net "P3V3_AUX")
		)
		(pad "2" smd circle
			(at -0.40005 0)
			(size 0 0)
			(layers "B.Cu" "B.Mask" "B.Paste")
			(net "FM_PRSNT_CPU0_N")
		)
	)
	(footprint ""
		(layer "B.Cu")
		(at 77.6224 -174.960534 90)
		(property "Reference" "PR204"
			(at 0 0 90)
			(layer "B.SilkS")
			(hide yes)
			(effects
				(font
					(size 1.27 1.27)
				)
				(justify mirror)
			)
		)
		(property "Value" ""
			(at 0 0 90)
			(layer "B.Fab")
			(effects
				(font
					(size 1.27 1.27)
				)
				(justify mirror)
			)
		)
		(duplicate_pad_numbers_are_jumpers no)
		(fp_line
			(start 0.7874 -0.4064)
			(end -0.7874 -0.4064)
			(stroke
				(width 0.1524)
				(type default)
			)
			(layer "B.SilkS")
		)
		(fp_line
			(start -0.7874 -0.4064)
			(end -0.7874 0.4064)
			(stroke
				(width 0.1524)
				(type default)
			)
			(layer "B.SilkS")
		)
		(fp_line
			(start 0.7874 0.4064)
			(end 0.7874 -0.4064)
			(stroke
				(width 0.1524)
				(type default)
			)
			(layer "B.SilkS")
		)
		(fp_line
			(start -0.7874 0.4064)
			(end 0.7874 0.4064)
			(stroke
				(width 0.1524)
				(type default)
			)
			(layer "B.SilkS")
		)
		(fp_line
			(start 0.67945 -0.305054)
			(end 0.12065 -0.305054)
			(stroke
				(width 0.1)
				(type default)
			)
			(layer "B.Fab")
		)
		(fp_line
			(start 0.12065 -0.305054)
			(end 0.12065 -0.2794)
			(stroke
				(width 0.1)
				(type default)
			)
			(layer "B.Fab")
		)
		(fp_line
			(start -0.12065 -0.3048)
			(end -0.67945 -0.3048)
			(stroke
				(width 0.1)
				(type default)
			)
			(layer "B.Fab")
		)
		(fp_line
			(start -0.67945 -0.3048)
			(end -0.67945 0.3048)
			(stroke
				(width 0.1)
				(type default)
			)
			(layer "B.Fab")
		)
		(fp_line
			(start 0.12065 -0.2794)
			(end -0.12065 -0.2794)
			(stroke
				(width 0.1)
				(type default)
			)
			(layer "B.Fab")
		)
		(fp_line
			(start -0.12065 -0.2794)
			(end -0.12065 -0.3048)
			(stroke
				(width 0.1)
				(type default)
			)
			(layer "B.Fab")
		)
		(fp_line
			(start 0.12065 0.2794)
			(end 0.12065 0.3048)
			(stroke
				(width 0.1)
				(type default)
			)
			(layer "B.Fab")
		)
		(fp_line
			(start -0.120396 0.2794)
			(end 0.12065 0.2794)
			(stroke
				(width 0.1)
				(type default)
			)
			(layer "B.Fab")
		)
		(fp_line
			(start 0.67945 0.3048)
			(end 0.67945 -0.305054)
			(stroke
				(width 0.1)
				(type default)
			)
			(layer "B.Fab")
		)
		(fp_line
			(start 0.12065 0.3048)
			(end 0.67945 0.3048)
			(stroke
				(width 0.1)
				(type default)
			)
			(layer "B.Fab")
		)
		(fp_line
			(start -0.120396 0.3048)
			(end -0.120396 0.2794)
			(stroke
				(width 0.1)
				(type default)
			)
			(layer "B.Fab")
		)
		(fp_line
			(start -0.67945 0.3048)
			(end -0.120396 0.3048)
			(stroke
				(width 0.1)
				(type default)
			)
			(layer "B.Fab")
		)
		(pad "1" smd circle
			(at 0.40005 0 270)
			(size 0 0)
			(layers "B.Cu" "B.Mask" "B.Paste")
			(net "PVDDCR_CPU0_P1_VOS5")
		)
		(pad "2" smd circle
			(at -0.40005 0 270)
			(size 0 0)
			(layers "B.Cu" "B.Mask" "B.Paste")
			(net "PVDDCR_CPU0_P1")
		)
	)
	(footprint ""
		(layer "B.Cu")
		(at 147.032726 -408.517344 90)
		(property "Reference" "C6746"
			(at 0 0 90)
			(layer "B.SilkS")
			(hide yes)
			(effects
				(font
					(size 1.27 1.27)
				)
				(justify mirror)
			)
		)
		(property "Value" ""
			(at 0 0 90)
			(layer "B.Fab")
			(effects
				(font
					(size 1.27 1.27)
				)
				(justify mirror)
			)
		)
		(duplicate_pad_numbers_are_jumpers no)
		(fp_line
			(start 0.299974 -0.150114)
			(end -0.299974 -0.150114)
			(stroke
				(width 0.1)
				(type default)
			)
			(layer "B.Fab")
		)
		(fp_line
			(start -0.299974 -0.150114)
			(end -0.299974 0.150114)
			(stroke
				(width 0.1)
				(type default)
			)
			(layer "B.Fab")
		)
		(fp_line
			(start 0.299974 0.150114)
			(end 0.299974 -0.150114)
			(stroke
				(width 0.1)
				(type default)
			)
			(layer "B.Fab")
		)
		(fp_line
			(start -0.299974 0.150114)
			(end 0.299974 0.150114)
			(stroke
				(width 0.1)
				(type default)
			)
			(layer "B.Fab")
		)
		(pad "1" smd rect
			(at 0.2667 0 270)
			(size 0.3048 0.381)
			(layers "B.Cu" "B.Mask" "B.Paste")
			(net "P5E_CPU1_P3_TX_BUF_C_DN<10>")
		)
		(pad "2" smd rect
			(at -0.2667 0 270)
			(size 0.3048 0.381)
			(layers "B.Cu" "B.Mask" "B.Paste")
			(net "P5E_CPU1_P3_TX_BUF_DN<10>")
		)
	)
)
